FILE_TYPE = CONNECTIVITY;
{Allegro Design Entry HDL 17.4-2019 S026 (4007227) 1/17/2022}
"PAGE_NUMBER" = 414;
0"NC";
END.
